(kicad_pcb
	(version 20260206)
	(generator "pcbnew")
	(generator_version "10.0")
	(general
		(thickness 1.6)
		(legacy_teardrops no)
	)
	(paper "A4")
	(title_block
		(title "01162023_DA0F0TEBIF0_F0T_Expander_BD_F_brd_V02_OCP.brd")
		(comment 1 "Grand Teton / footprints 7720-7727 of 9728")
	)
	(layers
		(0 "F.Cu" signal "TOP")
		(4 "In1.Cu" signal "GND")
		(6 "In2.Cu" signal "VCC")
		(8 "In3.Cu" signal "VCC1")
		(10 "In4.Cu" signal "GND1")
		(12 "In5.Cu" signal "IN1")
		(14 "In6.Cu" signal "GND2")
		(16 "In7.Cu" signal "IN2")
		(18 "In8.Cu" signal "GND3")
		(20 "In9.Cu" signal "IN3")
		(22 "In10.Cu" signal "GND4")
		(24 "In11.Cu" signal "IN4")
		(26 "In12.Cu" signal "GND5")
		(28 "In13.Cu" signal "IN5")
		(30 "In14.Cu" signal "GND6")
		(32 "In15.Cu" signal "IN6")
		(34 "In16.Cu" signal "GND7")
		(2 "B.Cu" signal "BOTTOM")
		(9 "F.Adhes" user "F.Adhesive")
		(11 "B.Adhes" user "B.Adhesive")
		(13 "F.Paste" user "Package Geometry/Pastemask Top")
		(15 "B.Paste" user "Package Geometry/Pastemask Bottom")
		(5 "F.SilkS" user "Ref Des/Silkscreen Top")
		(7 "B.SilkS" user "Ref Des/Silkscreen Bottom")
		(1 "F.Mask" user "Board Geometry/Soldermask Top")
		(3 "B.Mask" user "Board Geometry/Soldermask Bottom")
		(17 "Dwgs.User" user "User.Drawings")
		(19 "Cmts.User" user "User.Comments")
		(21 "Eco1.User" user "User.Eco1")
		(23 "Eco2.User" user "User.Eco2")
		(25 "Edge.Cuts" user "Board Geometry/Outline")
		(27 "Margin" user)
		(31 "F.CrtYd" user "Package Geometry/Place Bound Top")
		(29 "B.CrtYd" user "Package Geometry/Place Bound Bottom")
		(35 "F.Fab" user "Ref Des/Assembly Top")
		(33 "B.Fab" user "Ref Des/Assembly Bottom")
	)
	(footprint ""
		(layer "B.Cu")
		(at 340.423246 -87.875364)
		(property "Reference" "C2677"
			(at 0 0 0)
			(layer "B.SilkS")
			(hide yes)
			(effects
				(font
					(size 1.27 1.27)
				)
				(justify mirror)
			)
		)
		(property "Value" ""
			(at 0 0 0)
			(layer "B.Fab")
			(effects
				(font
					(size 1.27 1.27)
				)
				(justify mirror)
			)
		)
		(duplicate_pad_numbers_are_jumpers no)
		(fp_line
			(start -0.7874 -0.4064)
			(end -0.7874 0.4064)
			(stroke
				(width 0.1524)
				(type default)
			)
			(layer "B.SilkS")
		)
		(fp_line
			(start -0.7874 0.4064)
			(end 0.7874 0.4064)
			(stroke
				(width 0.1524)
				(type default)
			)
			(layer "B.SilkS")
		)
		(fp_line
			(start 0.7874 -0.4064)
			(end -0.7874 -0.4064)
			(stroke
				(width 0.1524)
				(type default)
			)
			(layer "B.SilkS")
		)
		(fp_line
			(start 0.7874 0.4064)
			(end 0.7874 -0.4064)
			(stroke
				(width 0.1524)
				(type default)
			)
			(layer "B.SilkS")
		)
		(fp_line
			(start -0.67945 -0.3048)
			(end -0.67945 0.3048)
			(stroke
				(width 0.1)
				(type default)
			)
			(layer "B.Fab")
		)
		(fp_line
			(start -0.67945 0.3048)
			(end -0.120396 0.3048)
			(stroke
				(width 0.1)
				(type default)
			)
			(layer "B.Fab")
		)
		(fp_line
			(start -0.12065 -0.3048)
			(end -0.67945 -0.3048)
			(stroke
				(width 0.1)
				(type default)
			)
			(layer "B.Fab")
		)
		(fp_line
			(start -0.12065 -0.2794)
			(end -0.12065 -0.3048)
			(stroke
				(width 0.1)
				(type default)
			)
			(layer "B.Fab")
		)
		(fp_line
			(start -0.120396 0.2794)
			(end 0.12065 0.2794)
			(stroke
				(width 0.1)
				(type default)
			)
			(layer "B.Fab")
		)
		(fp_line
			(start -0.120396 0.3048)
			(end -0.120396 0.2794)
			(stroke
				(width 0.1)
				(type default)
			)
			(layer "B.Fab")
		)
		(fp_line
			(start 0.12065 -0.305054)
			(end 0.12065 -0.2794)
			(stroke
				(width 0.1)
				(type default)
			)
			(layer "B.Fab")
		)
		(fp_line
			(start 0.12065 -0.2794)
			(end -0.12065 -0.2794)
			(stroke
				(width 0.1)
				(type default)
			)
			(layer "B.Fab")
		)
		(fp_line
			(start 0.12065 0.2794)
			(end 0.12065 0.3048)
			(stroke
				(width 0.1)
				(type default)
			)
			(layer "B.Fab")
		)
		(fp_line
			(start 0.12065 0.3048)
			(end 0.67945 0.3048)
			(stroke
				(width 0.1)
				(type default)
			)
			(layer "B.Fab")
		)
		(fp_line
			(start 0.67945 -0.305054)
			(end 0.12065 -0.305054)
			(stroke
				(width 0.1)
				(type default)
			)
			(layer "B.Fab")
		)
		(fp_line
			(start 0.67945 0.3048)
			(end 0.67945 -0.305054)
			(stroke
				(width 0.1)
				(type default)
			)
			(layer "B.Fab")
		)
		(pad "1" smd circle
			(at 0.40005 0 180)
			(size 0 0)
			(layers "B.Cu" "B.Mask" "B.Paste")
			(net "P3V3_VDD_9ZXL0851_8_15")
		)
		(pad "2" smd circle
			(at -0.40005 0 180)
			(size 0 0)
			(layers "B.Cu" "B.Mask" "B.Paste")
			(net "GND")
		)
	)
	(footprint ""
		(layer "B.Cu")
		(at 301.449232 -115.613434 -90)
		(property "Reference" "U33"
			(at 0.690118 4.357116 0)
			(unlocked yes)
			(layer "B.SilkS")
			(effects
				(font
					(size 0.7874 0.5842)
					(thickness 0.1524)
				)
				(justify mirror)
			)
		)
		(property "Value" ""
			(at 0 0 90)
			(layer "B.Fab")
			(effects
				(font
					(size 1.27 1.27)
				)
				(justify mirror)
			)
		)
		(duplicate_pad_numbers_are_jumpers no)
		(fp_line
			(start -1.3462 1.1938)
			(end -1.3462 -1.1938)
			(stroke
				(width 0.1524)
				(type default)
			)
			(layer "B.SilkS")
		)
		(fp_line
			(start 1.3462 1.1938)
			(end -1.3462 1.1938)
			(stroke
				(width 0.1524)
				(type default)
			)
			(layer "B.SilkS")
		)
		(fp_line
			(start -1.3462 -1.1938)
			(end 1.3462 -1.1938)
			(stroke
				(width 0.1524)
				(type default)
			)
			(layer "B.SilkS")
		)
		(fp_line
			(start 1.3462 -1.1938)
			(end 1.3462 1.1684)
			(stroke
				(width 0.1524)
				(type default)
			)
			(layer "B.SilkS")
		)
		(fp_poly
			(pts
				(xy 1.447038 -0.760476) (xy 2.052066 -0.457962) (xy 2.052066 -1.06299)
			)
			(stroke
				(width 0)
				(type default)
			)
			(fill yes)
			(layer "B.SilkS")
		)
		(fp_line
			(start -0.674878 1.124966)
			(end -0.674878 -1.124966)
			(stroke
				(width 0.1)
				(type default)
			)
			(layer "B.Fab")
		)
		(fp_line
			(start 0.674878 1.124966)
			(end -0.674878 1.124966)
			(stroke
				(width 0.1)
				(type default)
			)
			(layer "B.Fab")
		)
		(fp_line
			(start -0.674878 -1.124966)
			(end 0.674878 -1.124966)
			(stroke
				(width 0.1)
				(type default)
			)
			(layer "B.Fab")
		)
		(fp_line
			(start 0.674878 -1.124966)
			(end 0.674878 1.124966)
			(stroke
				(width 0.1)
				(type default)
			)
			(layer "B.Fab")
		)
		(fp_poly
			(pts
				(xy 1.447038 -0.760476) (xy 2.052066 -0.457962) (xy 2.052066 -1.06299)
			)
			(stroke
				(width 0)
				(type default)
			)
			(fill yes)
			(layer "B.Fab")
		)
		(pad "1" smd rect
			(at 0.899922 -0.750062 90)
			(size 0.6096 0.6096)
			(layers "B.Cu" "B.Mask" "B.Paste")
			(net "NIC5_AUX_PWR_EN_R")
		)
		(pad "2" smd rect
			(at 0.899922 0)
			(size 0.4064 0.6096)
			(layers "B.Cu" "B.Mask" "B.Paste")
			(net "RST_SMB_NIC5_MUX_N")
		)
		(pad "3" smd rect
			(at 0.899922 0.750062 90)
			(size 0.6096 0.6096)
			(layers "B.Cu" "B.Mask" "B.Paste")
			(net "GND")
		)
		(pad "4" smd rect
			(at -0.899922 0.750062 90)
			(size 0.6096 0.6096)
			(layers "B.Cu" "B.Mask" "B.Paste")
			(net "RST_SMB_NIC5_MUX_ISO_N")
		)
		(pad "5" smd rect
			(at -0.899922 -0.750062 90)
			(size 0.6096 0.6096)
			(layers "B.Cu" "B.Mask" "B.Paste")
			(net "P3V3_AUX")
		)
	)
	(footprint ""
		(layer "B.Cu")
		(at 131.129278 -211.242148)
		(property "Reference" "C2611"
			(at 0 0 0)
			(layer "B.SilkS")
			(hide yes)
			(effects
				(font
					(size 1.27 1.27)
				)
				(justify mirror)
			)
		)
		(property "Value" ""
			(at 0 0 0)
			(layer "B.Fab")
			(effects
				(font
					(size 1.27 1.27)
				)
				(justify mirror)
			)
		)
		(duplicate_pad_numbers_are_jumpers no)
		(fp_line
			(start -0.7874 -0.4064)
			(end -0.7874 0.4064)
			(stroke
				(width 0.1524)
				(type default)
			)
			(layer "B.SilkS")
		)
		(fp_line
			(start -0.7874 0.4064)
			(end 0.7874 0.4064)
			(stroke
				(width 0.1524)
				(type default)
			)
			(layer "B.SilkS")
		)
		(fp_line
			(start 0.7874 -0.4064)
			(end -0.7874 -0.4064)
			(stroke
				(width 0.1524)
				(type default)
			)
			(layer "B.SilkS")
		)
		(fp_line
			(start 0.7874 0.4064)
			(end 0.7874 -0.4064)
			(stroke
				(width 0.1524)
				(type default)
			)
			(layer "B.SilkS")
		)
		(fp_line
			(start -0.67945 -0.3048)
			(end -0.67945 0.3048)
			(stroke
				(width 0.1)
				(type default)
			)
			(layer "B.Fab")
		)
		(fp_line
			(start -0.67945 0.3048)
			(end -0.120396 0.3048)
			(stroke
				(width 0.1)
				(type default)
			)
			(layer "B.Fab")
		)
		(fp_line
			(start -0.12065 -0.3048)
			(end -0.67945 -0.3048)
			(stroke
				(width 0.1)
				(type default)
			)
			(layer "B.Fab")
		)
		(fp_line
			(start -0.12065 -0.2794)
			(end -0.12065 -0.3048)
			(stroke
				(width 0.1)
				(type default)
			)
			(layer "B.Fab")
		)
		(fp_line
			(start -0.120396 0.2794)
			(end 0.12065 0.2794)
			(stroke
				(width 0.1)
				(type default)
			)
			(layer "B.Fab")
		)
		(fp_line
			(start -0.120396 0.3048)
			(end -0.120396 0.2794)
			(stroke
				(width 0.1)
				(type default)
			)
			(layer "B.Fab")
		)
		(fp_line
			(start 0.12065 -0.305054)
			(end 0.12065 -0.2794)
			(stroke
				(width 0.1)
				(type default)
			)
			(layer "B.Fab")
		)
		(fp_line
			(start 0.12065 -0.2794)
			(end -0.12065 -0.2794)
			(stroke
				(width 0.1)
				(type default)
			)
			(layer "B.Fab")
		)
		(fp_line
			(start 0.12065 0.2794)
			(end 0.12065 0.3048)
			(stroke
				(width 0.1)
				(type default)
			)
			(layer "B.Fab")
		)
		(fp_line
			(start 0.12065 0.3048)
			(end 0.67945 0.3048)
			(stroke
				(width 0.1)
				(type default)
			)
			(layer "B.Fab")
		)
		(fp_line
			(start 0.67945 -0.305054)
			(end 0.12065 -0.305054)
			(stroke
				(width 0.1)
				(type default)
			)
			(layer "B.Fab")
		)
		(fp_line
			(start 0.67945 0.3048)
			(end 0.67945 -0.305054)
			(stroke
				(width 0.1)
				(type default)
			)
			(layer "B.Fab")
		)
		(pad "1" smd circle
			(at 0.40005 0 180)
			(size 0 0)
			(layers "B.Cu" "B.Mask" "B.Paste")
			(net "GND")
		)
		(pad "2" smd circle
			(at -0.40005 0 180)
			(size 0 0)
			(layers "B.Cu" "B.Mask" "B.Paste")
			(net "P1V8_PEX")
		)
	)
	(footprint ""
		(layer "B.Cu")
		(at 393.629642 -360.387138 180)
		(property "Reference" "R5472"
			(at 0 0 0)
			(layer "B.SilkS")
			(hide yes)
			(effects
				(font
					(size 1.27 1.27)
				)
				(justify mirror)
			)
		)
		(property "Value" ""
			(at 0 0 0)
			(layer "B.Fab")
			(effects
				(font
					(size 1.27 1.27)
				)
				(justify mirror)
			)
		)
		(duplicate_pad_numbers_are_jumpers no)
		(fp_line
			(start 0.7874 0.4064)
			(end 0.7874 -0.4064)
			(stroke
				(width 0.1524)
				(type default)
			)
			(layer "B.SilkS")
		)
		(fp_line
			(start 0.7874 -0.4064)
			(end -0.7874 -0.4064)
			(stroke
				(width 0.1524)
				(type default)
			)
			(layer "B.SilkS")
		)
		(fp_line
			(start -0.7874 0.4064)
			(end 0.7874 0.4064)
			(stroke
				(width 0.1524)
				(type default)
			)
			(layer "B.SilkS")
		)
		(fp_line
			(start -0.7874 -0.4064)
			(end -0.7874 0.4064)
			(stroke
				(width 0.1524)
				(type default)
			)
			(layer "B.SilkS")
		)
		(fp_line
			(start 0.67945 0.3048)
			(end 0.67945 -0.305054)
			(stroke
				(width 0.1)
				(type default)
			)
			(layer "B.Fab")
		)
		(fp_line
			(start 0.67945 -0.305054)
			(end 0.12065 -0.305054)
			(stroke
				(width 0.1)
				(type default)
			)
			(layer "B.Fab")
		)
		(fp_line
			(start 0.12065 0.3048)
			(end 0.67945 0.3048)
			(stroke
				(width 0.1)
				(type default)
			)
			(layer "B.Fab")
		)
		(fp_line
			(start 0.12065 0.2794)
			(end 0.12065 0.3048)
			(stroke
				(width 0.1)
				(type default)
			)
			(layer "B.Fab")
		)
		(fp_line
			(start 0.12065 -0.2794)
			(end -0.12065 -0.2794)
			(stroke
				(width 0.1)
				(type default)
			)
			(layer "B.Fab")
		)
		(fp_line
			(start 0.12065 -0.305054)
			(end 0.12065 -0.2794)
			(stroke
				(width 0.1)
				(type default)
			)
			(layer "B.Fab")
		)
		(fp_line
			(start -0.120396 0.3048)
			(end -0.120396 0.2794)
			(stroke
				(width 0.1)
				(type default)
			)
			(layer "B.Fab")
		)
		(fp_line
			(start -0.120396 0.2794)
			(end 0.12065 0.2794)
			(stroke
				(width 0.1)
				(type default)
			)
			(layer "B.Fab")
		)
		(fp_line
			(start -0.12065 -0.2794)
			(end -0.12065 -0.3048)
			(stroke
				(width 0.1)
				(type default)
			)
			(layer "B.Fab")
		)
		(fp_line
			(start -0.12065 -0.3048)
			(end -0.67945 -0.3048)
			(stroke
				(width 0.1)
				(type default)
			)
			(layer "B.Fab")
		)
		(fp_line
			(start -0.67945 0.3048)
			(end -0.120396 0.3048)
			(stroke
				(width 0.1)
				(type default)
			)
			(layer "B.Fab")
		)
		(fp_line
			(start -0.67945 -0.3048)
			(end -0.67945 0.3048)
			(stroke
				(width 0.1)
				(type default)
			)
			(layer "B.Fab")
		)
		(pad "1" smd circle
			(at 0.40005 0)
			(size 0 0)
			(layers "B.Cu" "B.Mask" "B.Paste")
			(net "UART_MB_BIC_R_RX")
		)
		(pad "2" smd circle
			(at -0.40005 0)
			(size 0 0)
			(layers "B.Cu" "B.Mask" "B.Paste")
			(net "UART_MB_BIC_RX")
		)
	)
	(footprint ""
		(layer "B.Cu")
		(at 196.689218 -368.95786 90)
		(property "Reference" "R6250"
			(at 0 0 90)
			(layer "B.SilkS")
			(hide yes)
			(effects
				(font
					(size 1.27 1.27)
				)
				(justify mirror)
			)
		)
		(property "Value" ""
			(at 0 0 90)
			(layer "B.Fab")
			(effects
				(font
					(size 1.27 1.27)
				)
				(justify mirror)
			)
		)
		(duplicate_pad_numbers_are_jumpers no)
		(fp_line
			(start 0.7874 -0.4064)
			(end -0.7874 -0.4064)
			(stroke
				(width 0.1524)
				(type default)
			)
			(layer "B.SilkS")
		)
		(fp_line
			(start -0.7874 -0.4064)
			(end -0.7874 0.4064)
			(stroke
				(width 0.1524)
				(type default)
			)
			(layer "B.SilkS")
		)
		(fp_line
			(start 0.7874 0.4064)
			(end 0.7874 -0.4064)
			(stroke
				(width 0.1524)
				(type default)
			)
			(layer "B.SilkS")
		)
		(fp_line
			(start -0.7874 0.4064)
			(end 0.7874 0.4064)
			(stroke
				(width 0.1524)
				(type default)
			)
			(layer "B.SilkS")
		)
		(fp_line
			(start 0.67945 -0.305054)
			(end 0.12065 -0.305054)
			(stroke
				(width 0.1)
				(type default)
			)
			(layer "B.Fab")
		)
		(fp_line
			(start 0.12065 -0.305054)
			(end 0.12065 -0.2794)
			(stroke
				(width 0.1)
				(type default)
			)
			(layer "B.Fab")
		)
		(fp_line
			(start -0.12065 -0.3048)
			(end -0.67945 -0.3048)
			(stroke
				(width 0.1)
				(type default)
			)
			(layer "B.Fab")
		)
		(fp_line
			(start -0.67945 -0.3048)
			(end -0.67945 0.3048)
			(stroke
				(width 0.1)
				(type default)
			)
			(layer "B.Fab")
		)
		(fp_line
			(start 0.12065 -0.2794)
			(end -0.12065 -0.2794)
			(stroke
				(width 0.1)
				(type default)
			)
			(layer "B.Fab")
		)
		(fp_line
			(start -0.12065 -0.2794)
			(end -0.12065 -0.3048)
			(stroke
				(width 0.1)
				(type default)
			)
			(layer "B.Fab")
		)
		(fp_line
			(start 0.12065 0.2794)
			(end 0.12065 0.3048)
			(stroke
				(width 0.1)
				(type default)
			)
			(layer "B.Fab")
		)
		(fp_line
			(start -0.120396 0.2794)
			(end 0.12065 0.2794)
			(stroke
				(width 0.1)
				(type default)
			)
			(layer "B.Fab")
		)
		(fp_line
			(start 0.67945 0.3048)
			(end 0.67945 -0.305054)
			(stroke
				(width 0.1)
				(type default)
			)
			(layer "B.Fab")
		)
		(fp_line
			(start 0.12065 0.3048)
			(end 0.67945 0.3048)
			(stroke
				(width 0.1)
				(type default)
			)
			(layer "B.Fab")
		)
		(fp_line
			(start -0.120396 0.3048)
			(end -0.120396 0.2794)
			(stroke
				(width 0.1)
				(type default)
			)
			(layer "B.Fab")
		)
		(fp_line
			(start -0.67945 0.3048)
			(end -0.120396 0.3048)
			(stroke
				(width 0.1)
				(type default)
			)
			(layer "B.Fab")
		)
		(pad "1" smd circle
			(at 0.40005 0 270)
			(size 0 0)
			(layers "B.Cu" "B.Mask" "B.Paste")
			(net "FM_HSC_PWROK")
		)
		(pad "2" smd circle
			(at -0.40005 0 270)
			(size 0 0)
			(layers "B.Cu" "B.Mask" "B.Paste")
			(net "AGND_HSC")
		)
	)
	(footprint ""
		(layer "B.Cu")
		(at 404.56993 -305.399948 -90)
		(property "Reference" "C3488"
			(at 0 0 90)
			(layer "B.SilkS")
			(hide yes)
			(effects
				(font
					(size 1.27 1.27)
				)
				(justify mirror)
			)
		)
		(property "Value" ""
			(at 0 0 90)
			(layer "B.Fab")
			(effects
				(font
					(size 1.27 1.27)
				)
				(justify mirror)
			)
		)
		(duplicate_pad_numbers_are_jumpers no)
		(fp_line
			(start -0.299974 0.150114)
			(end 0.299974 0.150114)
			(stroke
				(width 0.1)
				(type default)
			)
			(layer "B.Fab")
		)
		(fp_line
			(start 0.299974 0.150114)
			(end 0.299974 -0.150114)
			(stroke
				(width 0.1)
				(type default)
			)
			(layer "B.Fab")
		)
		(fp_line
			(start -0.299974 -0.150114)
			(end -0.299974 0.150114)
			(stroke
				(width 0.1)
				(type default)
			)
			(layer "B.Fab")
		)
		(fp_line
			(start 0.299974 -0.150114)
			(end -0.299974 -0.150114)
			(stroke
				(width 0.1)
				(type default)
			)
			(layer "B.Fab")
		)
		(pad "1" smd rect
			(at 0.2667 0 90)
			(size 0.3048 0.381)
			(layers "B.Cu" "B.Mask" "B.Paste")
			(net "P1V25_SERDES_VDDPLL_PEX3")
		)
		(pad "2" smd rect
			(at -0.2667 0 90)
			(size 0.3048 0.381)
			(layers "B.Cu" "B.Mask" "B.Paste")
			(net "GND")
		)
	)
	(footprint ""
		(layer "B.Cu")
		(at 392.749786 -293.04996)
		(property "Reference" "C3522"
			(at 0 0 0)
			(layer "B.SilkS")
			(hide yes)
			(effects
				(font
					(size 1.27 1.27)
				)
				(justify mirror)
			)
		)
		(property "Value" ""
			(at 0 0 0)
			(layer "B.Fab")
			(effects
				(font
					(size 1.27 1.27)
				)
				(justify mirror)
			)
		)
		(duplicate_pad_numbers_are_jumpers no)
		(fp_line
			(start -0.299974 -0.150114)
			(end -0.299974 0.150114)
			(stroke
				(width 0.1)
				(type default)
			)
			(layer "B.Fab")
		)
		(fp_line
			(start -0.299974 0.150114)
			(end 0.299974 0.150114)
			(stroke
				(width 0.1)
				(type default)
			)
			(layer "B.Fab")
		)
		(fp_line
			(start 0.299974 -0.150114)
			(end -0.299974 -0.150114)
			(stroke
				(width 0.1)
				(type default)
			)
			(layer "B.Fab")
		)
		(fp_line
			(start 0.299974 0.150114)
			(end 0.299974 -0.150114)
			(stroke
				(width 0.1)
				(type default)
			)
			(layer "B.Fab")
		)
		(pad "1" smd rect
			(at 0.2667 0 180)
			(size 0.3048 0.381)
			(layers "B.Cu" "B.Mask" "B.Paste")
			(net "P1V8_PEX")
		)
		(pad "2" smd rect
			(at -0.2667 0 180)
			(size 0.3048 0.381)
			(layers "B.Cu" "B.Mask" "B.Paste")
			(net "GND")
		)
	)
	(footprint ""
		(layer "B.Cu")
		(at 402.249894 -303.499774 -90)
		(property "Reference" "C3436"
			(at 0 0 90)
			(layer "B.SilkS")
			(hide yes)
			(effects
				(font
					(size 1.27 1.27)
				)
				(justify mirror)
			)
		)
		(property "Value" ""
			(at 0 0 90)
			(layer "B.Fab")
			(effects
				(font
					(size 1.27 1.27)
				)
				(justify mirror)
			)
		)
		(duplicate_pad_numbers_are_jumpers no)
		(fp_line
			(start -0.299974 0.150114)
			(end 0.299974 0.150114)
			(stroke
				(width 0.1)
				(type default)
			)
			(layer "B.Fab")
		)
		(fp_line
			(start 0.299974 0.150114)
			(end 0.299974 -0.150114)
			(stroke
				(width 0.1)
				(type default)
			)
			(layer "B.Fab")
		)
		(fp_line
			(start -0.299974 -0.150114)
			(end -0.299974 0.150114)
			(stroke
				(width 0.1)
				(type default)
			)
			(layer "B.Fab")
		)
		(fp_line
			(start 0.299974 -0.150114)
			(end -0.299974 -0.150114)
			(stroke
				(width 0.1)
				(type default)
			)
			(layer "B.Fab")
		)
		(pad "1" smd rect
			(at 0.2667 0 90)
			(size 0.3048 0.381)
			(layers "B.Cu" "B.Mask" "B.Paste")
			(net "P1V25_PEX3")
		)
		(pad "2" smd rect
			(at -0.2667 0 90)
			(size 0.3048 0.381)
			(layers "B.Cu" "B.Mask" "B.Paste")
			(net "GND")
		)
	)
)
